# S9S_MB_2U (Grand Teton) — schematic netlist excerpt (pin names and nets, part order shuffled) for the footprints in the layout excerpt that follows; sources: Cadence DE-HDL packaged netlist, KiCad conversion of 03242023_DA0F0TMBIJ0_F0T_Motherboard_J_brd_V01_OCP.brd

C551  Q_CAP  1UF 25V 10% X6S  pkg C0402  page 131 : A = P3V3_AUX ; B = GND
R4637  Q_RES  200K 1% CHIP  pkg 0402LF  page 169 : A = USB3_PCH_RX_DN<4> ; B = GND

(kicad_pcb
	(version 20260206)
	(generator "pcbnew")
	(generator_version "10.0")
	(general
		(thickness 1.6)
		(legacy_teardrops no)
	)
	(paper "A4")
	(title_block
		(title "03242023_DA0F0TMBIJ0_F0T_Motherboard_J_brd_V01_OCP.brd")
		(comment 1 "Grand Teton / footprints 5911-5912 of 6105")
	)
	(layers
		(0 "F.Cu" signal "TOP")
		(4 "In1.Cu" signal "GND")
		(6 "In2.Cu" signal "IN1")
		(8 "In3.Cu" signal "GND1")
		(10 "In4.Cu" signal "IN2")
		(12 "In5.Cu" signal "GND2")
		(14 "In6.Cu" signal "IN3")
		(16 "In7.Cu" signal "GND3")
		(18 "In8.Cu" signal "VCC")
		(20 "In9.Cu" signal "VCC1")
		(22 "In10.Cu" signal "GND4")
		(24 "In11.Cu" signal "IN4")
		(26 "In12.Cu" signal "GND5")
		(28 "In13.Cu" signal "IN5")
		(30 "In14.Cu" signal "GND6")
		(32 "In15.Cu" signal "IN6")
		(34 "In16.Cu" signal "GND7")
		(2 "B.Cu" signal "BOTTOM")
		(9 "F.Adhes" user "F.Adhesive")
		(11 "B.Adhes" user "B.Adhesive")
		(13 "F.Paste" user "Package Geometry/Pastemask Top")
		(15 "B.Paste" user "Package Geometry/Pastemask Bottom")
		(5 "F.SilkS" user "Ref Des/Silkscreen Top")
		(7 "B.SilkS" user "Ref Des/Silkscreen Bottom")
		(1 "F.Mask" user "Board Geometry/Soldermask Top")
		(3 "B.Mask" user "Board Geometry/Soldermask Bottom")
		(17 "Dwgs.User" user "User.Drawings")
		(19 "Cmts.User" user "User.Comments")
		(21 "Eco1.User" user "User.Eco1")
		(23 "Eco2.User" user "User.Eco2")
		(25 "Edge.Cuts" user "Board Geometry/Outline")
		(27 "Margin" user)
		(31 "F.CrtYd" user "Package Geometry/Place Bound Top")
		(29 "B.CrtYd" user "Package Geometry/Place Bound Bottom")
		(35 "F.Fab" user "Ref Des/Assembly Top")
		(33 "B.Fab" user "Ref Des/Assembly Bottom")
	)
	(footprint ""
		(layer "B.Cu")
		(at 133.5786 -26.8732 90)
		(property "Reference" "R4637"
			(at 0 0 90)
			(layer "B.SilkS")
			(hide yes)
			(effects
				(font
					(size 1.27 1.27)
				)
				(justify mirror)
			)
		)
		(property "Value" ""
			(at 0 0 90)
			(layer "B.Fab")
			(effects
				(font
					(size 1.27 1.27)
				)
				(justify mirror)
			)
		)
		(duplicate_pad_numbers_are_jumpers no)
		(fp_line
			(start 0.7874 -0.4064)
			(end -0.7874 -0.4064)
			(stroke
				(width 0.1524)
				(type default)
			)
			(layer "B.SilkS")
		)
		(fp_line
			(start -0.7874 -0.4064)
			(end -0.7874 0.4064)
			(stroke
				(width 0.1524)
				(type default)
			)
			(layer "B.SilkS")
		)
		(fp_line
			(start 0.7874 0.4064)
			(end 0.7874 -0.4064)
			(stroke
				(width 0.1524)
				(type default)
			)
			(layer "B.SilkS")
		)
		(fp_line
			(start -0.7874 0.4064)
			(end 0.7874 0.4064)
			(stroke
				(width 0.1524)
				(type default)
			)
			(layer "B.SilkS")
		)
		(fp_line
			(start 0.67945 -0.305054)
			(end 0.12065 -0.305054)
			(stroke
				(width 0.1)
				(type default)
			)
			(layer "B.Fab")
		)
		(fp_line
			(start 0.12065 -0.305054)
			(end 0.12065 -0.2794)
			(stroke
				(width 0.1)
				(type default)
			)
			(layer "B.Fab")
		)
		(fp_line
			(start -0.12065 -0.3048)
			(end -0.67945 -0.3048)
			(stroke
				(width 0.1)
				(type default)
			)
			(layer "B.Fab")
		)
		(fp_line
			(start -0.67945 -0.3048)
			(end -0.67945 0.3048)
			(stroke
				(width 0.1)
				(type default)
			)
			(layer "B.Fab")
		)
		(fp_line
			(start 0.12065 -0.2794)
			(end -0.12065 -0.2794)
			(stroke
				(width 0.1)
				(type default)
			)
			(layer "B.Fab")
		)
		(fp_line
			(start -0.12065 -0.2794)
			(end -0.12065 -0.3048)
			(stroke
				(width 0.1)
				(type default)
			)
			(layer "B.Fab")
		)
		(fp_line
			(start 0.12065 0.2794)
			(end 0.12065 0.3048)
			(stroke
				(width 0.1)
				(type default)
			)
			(layer "B.Fab")
		)
		(fp_line
			(start -0.120396 0.2794)
			(end 0.12065 0.2794)
			(stroke
				(width 0.1)
				(type default)
			)
			(layer "B.Fab")
		)
		(fp_line
			(start 0.67945 0.3048)
			(end 0.67945 -0.305054)
			(stroke
				(width 0.1)
				(type default)
			)
			(layer "B.Fab")
		)
		(fp_line
			(start 0.12065 0.3048)
			(end 0.67945 0.3048)
			(stroke
				(width 0.1)
				(type default)
			)
			(layer "B.Fab")
		)
		(fp_line
			(start -0.120396 0.3048)
			(end -0.120396 0.2794)
			(stroke
				(width 0.1)
				(type default)
			)
			(layer "B.Fab")
		)
		(fp_line
			(start -0.67945 0.3048)
			(end -0.120396 0.3048)
			(stroke
				(width 0.1)
				(type default)
			)
			(layer "B.Fab")
		)
		(pad "1" smd circle
			(at 0.40005 0 270)
			(size 0 0)
			(layers "B.Cu" "B.Mask" "B.Paste")
			(net "USB3_PCH_RX_DN<4>")
		)
		(pad "2" smd circle
			(at -0.40005 0 270)
			(size 0 0)
			(layers "B.Cu" "B.Mask" "B.Paste")
			(net "GND")
		)
	)
	(footprint ""
		(layer "B.Cu")
		(at 396.72006 -50.864008 90)
		(property "Reference" "C551"
			(at 0 0 90)
			(layer "B.SilkS")
			(hide yes)
			(effects
				(font
					(size 1.27 1.27)
				)
				(justify mirror)
			)
		)
		(property "Value" ""
			(at 0 0 90)
			(layer "B.Fab")
			(effects
				(font
					(size 1.27 1.27)
				)
				(justify mirror)
			)
		)
		(duplicate_pad_numbers_are_jumpers no)
		(fp_line
			(start 0.7874 -0.4064)
			(end -0.7874 -0.4064)
			(stroke
				(width 0.1524)
				(type default)
			)
			(layer "B.SilkS")
		)
		(fp_line
			(start -0.7874 -0.4064)
			(end -0.7874 0.4064)
			(stroke
				(width 0.1524)
				(type default)
			)
			(layer "B.SilkS")
		)
		(fp_line
			(start 0.7874 0.4064)
			(end 0.7874 -0.4064)
			(stroke
				(width 0.1524)
				(type default)
			)
			(layer "B.SilkS")
		)
		(fp_line
			(start -0.7874 0.4064)
			(end 0.7874 0.4064)
			(stroke
				(width 0.1524)
				(type default)
			)
			(layer "B.SilkS")
		)
		(fp_line
			(start 0.67945 -0.305054)
			(end 0.12065 -0.305054)
			(stroke
				(width 0.1)
				(type default)
			)
			(layer "B.Fab")
		)
		(fp_line
			(start 0.12065 -0.305054)
			(end 0.12065 -0.2794)
			(stroke
				(width 0.1)
				(type default)
			)
			(layer "B.Fab")
		)
		(fp_line
			(start -0.12065 -0.3048)
			(end -0.67945 -0.3048)
			(stroke
				(width 0.1)
				(type default)
			)
			(layer "B.Fab")
		)
		(fp_line
			(start -0.67945 -0.3048)
			(end -0.67945 0.3048)
			(stroke
				(width 0.1)
				(type default)
			)
			(layer "B.Fab")
		)
		(fp_line
			(start 0.12065 -0.2794)
			(end -0.12065 -0.2794)
			(stroke
				(width 0.1)
				(type default)
			)
			(layer "B.Fab")
		)
		(fp_line
			(start -0.12065 -0.2794)
			(end -0.12065 -0.3048)
			(stroke
				(width 0.1)
				(type default)
			)
			(layer "B.Fab")
		)
		(fp_line
			(start 0.12065 0.2794)
			(end 0.12065 0.3048)
			(stroke
				(width 0.1)
				(type default)
			)
			(layer "B.Fab")
		)
		(fp_line
			(start -0.120396 0.2794)
			(end 0.12065 0.2794)
			(stroke
				(width 0.1)
				(type default)
			)
			(layer "B.Fab")
		)
		(fp_line
			(start 0.67945 0.3048)
			(end 0.67945 -0.305054)
			(stroke
				(width 0.1)
				(type default)
			)
			(layer "B.Fab")
		)
		(fp_line
			(start 0.12065 0.3048)
			(end 0.67945 0.3048)
			(stroke
				(width 0.1)
				(type default)
			)
			(layer "B.Fab")
		)
		(fp_line
			(start -0.120396 0.3048)
			(end -0.120396 0.2794)
			(stroke
				(width 0.1)
				(type default)
			)
			(layer "B.Fab")
		)
		(fp_line
			(start -0.67945 0.3048)
			(end -0.120396 0.3048)
			(stroke
				(width 0.1)
				(type default)
			)
			(layer "B.Fab")
		)
		(pad "1" smd circle
			(at 0.40005 0 270)
			(size 0 0)
			(layers "B.Cu" "B.Mask" "B.Paste")
			(net "P3V3_AUX")
		)
		(pad "2" smd circle
			(at -0.40005 0 270)
			(size 0 0)
			(layers "B.Cu" "B.Mask" "B.Paste")
			(net "GND")
		)
	)
)
